# S9S_MB_2U (Grand Teton) — schematic netlist excerpt (pin names and nets, part order shuffled) for the footprints in the layout excerpt that follows; sources: Cadence DE-HDL packaged netlist, KiCad conversion of 03242023_DA0F0TMBIJ0_F0T_Motherboard_J_brd_V01_OCP.brd

R3763  Q_RES  4.7K 1% CHIP  pkg 0402LF  page 171 : A = GND ; B = INA230_2_A1

Q97  MOSFET_NCH_DUAL  NX6008NBKS IC  pkg SOT363XB  page 256
  S1  = GND
  G1  = RST_PLD_CPU0_DRAM_EF_N
  D2  = LED_RST_PLD_CPU0_DRAM_GH_N_D
  S2  = GND
  G2  = RST_PLD_CPU0_DRAM_GH_N
  D1  = LED_RST_PLD_CPU0_DRAM_EF_N_D

(kicad_pcb
	(version 20260206)
	(generator "pcbnew")
	(generator_version "10.0")
	(general
		(thickness 1.6)
		(legacy_teardrops no)
	)
	(paper "A4")
	(title_block
		(title "03242023_DA0F0TMBIJ0_F0T_Motherboard_J_brd_V01_OCP.brd")
		(comment 1 "Grand Teton / footprints 1838-1839 of 6105")
	)
	(layers
		(0 "F.Cu" signal "TOP")
		(4 "In1.Cu" signal "GND")
		(6 "In2.Cu" signal "IN1")
		(8 "In3.Cu" signal "GND1")
		(10 "In4.Cu" signal "IN2")
		(12 "In5.Cu" signal "GND2")
		(14 "In6.Cu" signal "IN3")
		(16 "In7.Cu" signal "GND3")
		(18 "In8.Cu" signal "VCC")
		(20 "In9.Cu" signal "VCC1")
		(22 "In10.Cu" signal "GND4")
		(24 "In11.Cu" signal "IN4")
		(26 "In12.Cu" signal "GND5")
		(28 "In13.Cu" signal "IN5")
		(30 "In14.Cu" signal "GND6")
		(32 "In15.Cu" signal "IN6")
		(34 "In16.Cu" signal "GND7")
		(2 "B.Cu" signal "BOTTOM")
		(9 "F.Adhes" user "F.Adhesive")
		(11 "B.Adhes" user "B.Adhesive")
		(13 "F.Paste" user "Package Geometry/Pastemask Top")
		(15 "B.Paste" user "Package Geometry/Pastemask Bottom")
		(5 "F.SilkS" user "Ref Des/Silkscreen Top")
		(7 "B.SilkS" user "Ref Des/Silkscreen Bottom")
		(1 "F.Mask" user "Board Geometry/Soldermask Top")
		(3 "B.Mask" user "Board Geometry/Soldermask Bottom")
		(17 "Dwgs.User" user "User.Drawings")
		(19 "Cmts.User" user "User.Comments")
		(21 "Eco1.User" user "User.Eco1")
		(23 "Eco2.User" user "User.Eco2")
		(25 "Edge.Cuts" user "Board Geometry/Outline")
		(27 "Margin" user)
		(31 "F.CrtYd" user "Package Geometry/Place Bound Top")
		(29 "B.CrtYd" user "Package Geometry/Place Bound Bottom")
		(35 "F.Fab" user "Ref Des/Assembly Top")
		(33 "B.Fab" user "Ref Des/Assembly Bottom")
	)
	(footprint ""
		(layer "F.Cu")
		(at 94.045278 -96.176846)
		(property "Reference" "Q97"
			(at -3.64236 -0.033528 0)
			(unlocked yes)
			(layer "F.SilkS")
			(effects
				(font
					(size 0.7874 0.5842)
					(thickness 0.1524)
				)
			)
		)
		(property "Value" ""
			(at 0 0 0)
			(layer "F.Fab")
			(effects
				(font
					(size 1.27 1.27)
				)
			)
		)
		(duplicate_pad_numbers_are_jumpers no)
		(fp_line
			(start -1.376172 -1.199896)
			(end -0.508 -1.199896)
			(stroke
				(width 0.1524)
				(type default)
			)
			(layer "F.SilkS")
		)
		(fp_line
			(start -1.376172 1.199896)
			(end -1.376172 -1.199896)
			(stroke
				(width 0.1524)
				(type default)
			)
			(layer "F.SilkS")
		)
		(fp_line
			(start -0.508 -1.199896)
			(end 0 -0.762)
			(stroke
				(width 0.1524)
				(type default)
			)
			(layer "F.SilkS")
		)
		(fp_line
			(start 0 -0.762)
			(end 0.508 -1.199896)
			(stroke
				(width 0.1524)
				(type default)
			)
			(layer "F.SilkS")
		)
		(fp_line
			(start 0.508 -1.199896)
			(end 1.376172 -1.199896)
			(stroke
				(width 0.1524)
				(type default)
			)
			(layer "F.SilkS")
		)
		(fp_line
			(start 1.376172 -1.199896)
			(end 1.376172 1.199896)
			(stroke
				(width 0.1524)
				(type default)
			)
			(layer "F.SilkS")
		)
		(fp_line
			(start 1.376172 1.199896)
			(end -1.376172 1.199896)
			(stroke
				(width 0.1524)
				(type default)
			)
			(layer "F.SilkS")
		)
		(fp_poly
			(pts
				(xy -0.9144 -1.302004) (xy -1.2954 -2.064004) (xy -0.5334 -2.064004)
			)
			(stroke
				(width 0)
				(type default)
			)
			(fill yes)
			(layer "F.SilkS")
		)
		(fp_line
			(start -0.674878 -1.100074)
			(end 0.674878 -1.100074)
			(stroke
				(width 0.1)
				(type default)
			)
			(layer "F.Fab")
		)
		(fp_line
			(start -0.674878 1.100074)
			(end -0.674878 -1.100074)
			(stroke
				(width 0.1)
				(type default)
			)
			(layer "F.Fab")
		)
		(fp_line
			(start 0.674878 -1.100074)
			(end 0.674878 1.100074)
			(stroke
				(width 0.1)
				(type default)
			)
			(layer "F.Fab")
		)
		(fp_line
			(start 0.674878 1.100074)
			(end -0.674878 1.100074)
			(stroke
				(width 0.1)
				(type default)
			)
			(layer "F.Fab")
		)
		(fp_poly
			(pts
				(xy -1.4605 -0.7493) (xy -2.2225 -1.1303) (xy -2.2225 -0.3683)
			)
			(stroke
				(width 0)
				(type default)
			)
			(fill yes)
			(layer "F.Fab")
		)
		(pad "1" smd rect
			(at -0.899922 -0.750062 270)
			(size 0.6096 0.6096)
			(layers "F.Cu" "F.Mask" "F.Paste")
			(net "GND")
		)
		(pad "2" smd rect
			(at -0.899922 0 270)
			(size 0.4064 0.6096)
			(layers "F.Cu" "F.Mask" "F.Paste")
			(net "RST_PLD_CPU0_DRAM_EF_N")
		)
		(pad "3" smd rect
			(at -0.899922 0.750062 270)
			(size 0.6096 0.6096)
			(layers "F.Cu" "F.Mask" "F.Paste")
			(net "LED_RST_PLD_CPU0_DRAM_GH_N_D")
		)
		(pad "4" smd rect
			(at 0.899922 0.750062 270)
			(size 0.6096 0.6096)
			(layers "F.Cu" "F.Mask" "F.Paste")
			(net "GND")
		)
		(pad "5" smd rect
			(at 0.899922 0 270)
			(size 0.4064 0.6096)
			(layers "F.Cu" "F.Mask" "F.Paste")
			(net "RST_PLD_CPU0_DRAM_GH_N")
		)
		(pad "6" smd rect
			(at 0.899922 -0.750062 270)
			(size 0.6096 0.6096)
			(layers "F.Cu" "F.Mask" "F.Paste")
			(net "LED_RST_PLD_CPU0_DRAM_EF_N_D")
		)
	)
	(footprint ""
		(layer "F.Cu")
		(at 211.76361 -57.548272 -90)
		(property "Reference" "R3763"
			(at 0 0 270)
			(layer "F.SilkS")
			(hide yes)
			(effects
				(font
					(size 1.27 1.27)
				)
			)
		)
		(property "Value" ""
			(at 0 0 270)
			(layer "F.Fab")
			(effects
				(font
					(size 1.27 1.27)
				)
			)
		)
		(duplicate_pad_numbers_are_jumpers no)
		(fp_line
			(start -0.7874 0.4064)
			(end -0.7874 -0.4064)
			(stroke
				(width 0.1524)
				(type default)
			)
			(layer "F.SilkS")
		)
		(fp_line
			(start 0.7874 0.4064)
			(end -0.7874 0.4064)
			(stroke
				(width 0.1524)
				(type default)
			)
			(layer "F.SilkS")
		)
		(fp_line
			(start -0.7874 -0.4064)
			(end 0.7874 -0.4064)
			(stroke
				(width 0.1524)
				(type default)
			)
			(layer "F.SilkS")
		)
		(fp_line
			(start 0.7874 -0.4064)
			(end 0.7874 0.4064)
			(stroke
				(width 0.1524)
				(type default)
			)
			(layer "F.SilkS")
		)
		(fp_line
			(start -0.67945 0.3048)
			(end -0.67945 -0.305054)
			(stroke
				(width 0.1)
				(type default)
			)
			(layer "F.Fab")
		)
		(fp_line
			(start -0.12065 0.3048)
			(end -0.67945 0.3048)
			(stroke
				(width 0.1)
				(type default)
			)
			(layer "F.Fab")
		)
		(fp_line
			(start 0.120396 0.3048)
			(end 0.120396 0.2794)
			(stroke
				(width 0.1)
				(type default)
			)
			(layer "F.Fab")
		)
		(fp_line
			(start 0.67945 0.3048)
			(end 0.120396 0.3048)
			(stroke
				(width 0.1)
				(type default)
			)
			(layer "F.Fab")
		)
		(fp_line
			(start -0.12065 0.2794)
			(end -0.12065 0.3048)
			(stroke
				(width 0.1)
				(type default)
			)
			(layer "F.Fab")
		)
		(fp_line
			(start 0.120396 0.2794)
			(end -0.12065 0.2794)
			(stroke
				(width 0.1)
				(type default)
			)
			(layer "F.Fab")
		)
		(fp_line
			(start -0.12065 -0.2794)
			(end 0.12065 -0.2794)
			(stroke
				(width 0.1)
				(type default)
			)
			(layer "F.Fab")
		)
		(fp_line
			(start 0.12065 -0.2794)
			(end 0.12065 -0.3048)
			(stroke
				(width 0.1)
				(type default)
			)
			(layer "F.Fab")
		)
		(fp_line
			(start 0.12065 -0.3048)
			(end 0.67945 -0.3048)
			(stroke
				(width 0.1)
				(type default)
			)
			(layer "F.Fab")
		)
		(fp_line
			(start 0.67945 -0.3048)
			(end 0.67945 0.3048)
			(stroke
				(width 0.1)
				(type default)
			)
			(layer "F.Fab")
		)
		(fp_line
			(start -0.67945 -0.305054)
			(end -0.12065 -0.305054)
			(stroke
				(width 0.1)
				(type default)
			)
			(layer "F.Fab")
		)
		(fp_line
			(start -0.12065 -0.305054)
			(end -0.12065 -0.2794)
			(stroke
				(width 0.1)
				(type default)
			)
			(layer "F.Fab")
		)
		(pad "1" smd circle
			(at -0.40005 0 270)
			(size 0 0)
			(layers "F.Cu" "F.Mask" "F.Paste")
			(net "GND")
		)
		(pad "2" smd circle
			(at 0.40005 0 270)
			(size 0 0)
			(layers "F.Cu" "F.Mask" "F.Paste")
			(net "INA230_2_A1")
		)
	)
)
